# BARRELEYE_G2-FPDB_POST-EVT-HW-EBOM-X00_20161123-add_2nd_source_X08-20161215-Final-b.xls — DEPOP (bom)
| FOXCONN TECHNOLOGY GROUP |  |  |  |  |  |  |  |  |  |  |  |  |
| BILL OF MATERIAL |  |  |  |  |  |  |  |  |  |  |  |  |
| REV OF  BOM |  | CUSTOMER | <name> |  | CUSTOMER P/N |  | PRODUCT CODE |  | PWA  REV |  | DATE |  |
| Sourcing (Single/Sole/Multi) | Critical Commodity (Y or N) | Component Class (1, 2, other) | Customer PSL (Y or N) | Item Number | Foxconn P/N | Customer P/N | Part Description | Manufacturer  Full Name | Manufacturer  Part Number | Qty | RoHS Status | Location |
|  |  |  |  | 1 | 620105400-015-G |  | CAP,1uF,+/-10%,X7R,16V,G,SMD0603 | MURATA | GRM188R71C105K | 1 |  | C401 |
|  |  |  |  | 2 | 52040EC00-237-G |  | DIODE,Zener,MMSZ5246B-7-F,16V,7.8mA,G,SOD123-2,SMD | DIODES | MMSZ5246B-7-F | 1 |  | PHAD3 |
|  |  |  |  | 3 | 61010G500-017-G | - | RES,10KOhm,+/-1%,1/16W,G,SMD0402 | KOA | RK73H1ETTP1002F | 2 |  | PHAR3,R44 |
|  |  |  |  | 4 | 610107A00-017-G | - | RES,0 Ohm,+/-5%,1/16W,G,SMD0402 | KOA | RK73Z1ETTP | 30 |  | R5,R6,PSRR8,PHAR10,PHAR16,PHAR17,PHAR18,PHAR19,PHAR21,PHAR26,PHAR27,PHAR33,PHAR36,PHAR37,PHAR39,PHAR47,R56,R57,R70,R71,R84,R85,R1780,R1782,R1784,R1785,R1786,R1787,R1788,R1789 |
|  |  |  |  | 5 | 62010QB00-015-G | - | CAP,10nF,+/-10%,X7R,50V,G,SMD0402 | MURATA | GRM155R71H103K | 1 |  | PSRC9 |
|  |  |  |  | 6 | 620105U00-015-G | - | CAP,220pF,+/-10%,X7R,50V,G,SMD0402 | MURATA | GRM155R71H221K | 1 |  | PSRC13 |
|  |  |  |  | 7 | 61011HA00-017-G |  | RES,1 Ohm,+/-1%,1/16W,G,SMD0402 | KOA | RK73H1ETTP1R00F | 1 |  | PSRR14 |
|  |  |  |  | 8 | 61012JH00-017-G |  | RES,470 Ohm,+/-5%,1/8W,G,SMD0805 | KOA | RK73B2ATTD471J | 1 |  | PSRR20 |
|  |  |  |  | 9 | 61010JY00-017-G | - | RES,220 Ohm,+/-5%,1/16W,G,SMD0402 | KOA | RK73B1ETTP221J | 3 |  | R16,R38,R1774 |
|  |  |  |  | 10 | 61010L100-017-G | - | RES,100KOhm,+/-1%,1/16W,G,SMD0402 | KOA | RK73H1ETTP1003F | 1 |  | R24 |
|  |  |  |  | 11 | 61010LA00-017-G | - | RES,4.7KOhm,+/-1%,1/16W,G,SMD0402 | KOA | RK73H1ETTP4701F | 3 |  | R53,R1776,R1777 |
|  |  |  |  | 12 | 610103U00-017-G | - | RES,330 Ohm,+/-1%,1/10W,G,SMD0603 | KOA | RK73H1JTTD3300F | 12 |  | R63,R65,R67,R69,R77,R79,R81,R83,R91,R93,R95,R97 |
|  |  |  |  | 13 | 61011MQ00-017-G | - | RES,4.75KOhm,+/-1%,1/16W,G,SMD0402 | KOA | RK73H1ETTP4751F | 2 |  | R1769,R1773 |
|  |  |  |  | 14 | 61100LR00-017-G |  | RES,100 Ohm,+/-1%,1/16W,G,SMD0402 | KOA | RN731ETTP1000F50 | 1 |  | R1778 |
